FILE_TYPE = MULTI_PHYS_TABLE;

PART 'MOSFET_PCH_GDS'

{========================================================================================}
:VALUE              | PART_TYPE | MATERIAL | PART_NUMBER       = STANDARD        | LIFECYCLE          | PART_NUMBER       | JEDEC_TYPE                 | DESCRIPTION                                | MANUFTR | MANUF_PN           | RD_CMPLS_LVL | CMPLS_LVL | CLASS | DIP_SMD | FP_ECN                 | FROM_PJ        | DATA                                   | EE_CHECK_LIST | STATUS | PSL | PREFERENCE | CREATOR | CREATEDAY  ;
{========================================================================================}
 'DMG3415U-7'       | 'SMLF'    | 'IC'     | 'BAM34150000'(!)  = ''              | 'End of Life'      | 'BAM34150000'     |'SOT23_GDSXC_EOL'| 'TRANS MOS DMG3415U-7(-20V,-4A,0.9W)SOT23' | 'DDS'   | 'DMG3415U-7'       | ''           | 'EP(V1)'  | 'IC'  | ''      | ''                     | 'S1N-AI-JU'    | 'DDS_DMG3415U_REV3-2.pdf'              | ''            | ''     | ''  | ''         | ''      | '20120622'
 'DMG3415U-7'       | 'SMLF'    | 'EMPTY'  | 'BAM34150000'(!)  = ''              | 'End of Life'      | 'BAM34150000'     |'SOT23_GDSXC_EOL'| 'TRANS MOS DMG3415U-7(-20V,-4A,0.9W)SOT23' | 'DDS'   | 'DMG3415U-7'       | ''           | 'EP(V1)'  | 'IC'  | ''      | ''                     | 'S1N-AI-JU'    | 'DDS_DMG3415U_REV3-2.pdf'              | ''            | ''     | ''  | ''         | ''      | '20120622'
 'BSS84AK'          | 'SMLF'    | 'IC'     | 'BAM00840009'(!)  = ''              | ''                 | 'BAM00840009'     |'SOT23_GDSXE'| 'TRANS MOSFET BSS84AK(-50V,-0.18A,0.35W)'  | 'NXP'   | 'BSS84AK'          | 'EP(V1)'     | ''        | 'IC'  | ''      | ''                     | 'S1N-AIJU'     | 'NXP_BSS84AK.pdf'                      | ''            | ''     | ''  | ''         | ''      | '20130228'
 'BSS84AK'          | 'SMLF'    | 'EMPTY'  | 'BAM00840009'(!)  = ''              | ''                 | 'BAM00840009'     |'SOT23_GDSXE'| 'TRANS MOSFET BSS84AK(-50V,-0.18A,0.35W)'  | 'NXP'   | 'BSS84AK'          | 'EP(V1)'     | ''        | 'IC'  | ''      | ''                     | 'S1N-AIJU'     | 'NXP_BSS84AK.pdf'                      | ''            | ''     | ''  | ''         | ''      | '20130228'
 'FDN352AP'         | 'SMLF'    | 'IC'     | 'BAM03520001'(!)  = 'End of Design' | 'Comp-Approve'     | 'BAM03520001'     |'SOT23_GDS'| 'TRANS MOSFET FDN352AP(-30V,-1.3A)'        | 'FAC'   | 'FDN352AP'         | 'EP'         | 'EU(V1)'  | 'IC'  | ''      | ''                     | 'TU1J-OZ'      | 'FAC_FDN352AP.pdf'                     | ''            | ''     | ''  | ''         | ''      | '20130411'
 'FDN352AP'         | 'SMLF'    | 'EMPTY'  | 'BAM03520001'(!)  = 'End of Design' | 'Comp-Approve'     | 'BAM03520001'     |'SOT23_GDS'| 'TRANS MOSFET FDN352AP(-30V,-1.3A)'        | 'FAC'   | 'FDN352AP'         | 'EP'         | 'EU(V1)'  | 'IC'  | ''      | ''                     | 'TU1J-OZ'      | 'FAC_FDN352AP.pdf'                     | ''            | ''     | ''  | ''         | ''      | '20130411'
 'SI2333CDS-T1-GE3' | 'SMLF'    | 'IC'     | 'BAM23330000'(!)  = ''              | ''                 | 'BAM23330000'     |'SOT23_GDSXB'| 'TRANS MOS SI2333CDS-T1-GE3(12V,20A,2.5W)' | 'SIL'   | 'SI2333CDS-T1-GE3' | 'EP(V1)'     | 'EP(V1)'  | 'IC'  | ''      | ''                     | 'S2B-ALVIN'    | 'SIL_SI2333CDS.pdf'                    | ''            | ''     | ''  | ''         | ''      | '20131203'
 'SI2333CDS-T1-GE3' | 'SMLF'    | 'EMPTY'  | 'BAM23330000'(!)  = ''              | ''                 | 'BAM23330000'     |'SOT23_GDSXB'| 'TRANS MOS SI2333CDS-T1-GE3(12V,20A,2.5W)' | 'SIL'   | 'SI2333CDS-T1-GE3' | 'EP(V1)'     | 'EP(V1)'  | 'IC'  | ''      | ''                     | 'S2B-ALVIN'    | 'SIL_SI2333CDS.pdf'                    | ''            | ''     | ''  | ''         | ''      | '20131203'
 'SI2343DS-T1-E3'   | 'SMLF'    | 'IC'     | 'BAM23430000'(!)  = ''              | ''                 | 'BAM23430000'     |'SOT23_GDSXB'| 'TRANS MOS SI2343DS-T1-E3(30V,15A,1.25W)'  | 'SIL'   | 'SI2343DS-T1-E3'   | 'EP(V1)'     | 'EP(V1)'  | 'IC'  | ''      | ''                     | 'S2B-ALVIN'    | 'SIL_SI2343DS.pdf'                     | ''            | ''     | ''  | ''         | ''      | '20131205'
 'SI2343DS-T1-E3'   | 'SMLF'    | 'EMPTY'  | 'BAM23430000'(!)  = ''              | ''                 | 'BAM23430000'     |'SOT23_GDSXB'| 'TRANS MOS SI2343DS-T1-E3(30V,15A,1.25W)'  | 'SIL'   | 'SI2343DS-T1-E3'   | 'EP(V1)'     | 'EP(V1)'  | 'IC'  | ''      | ''                     | 'S2B-ALVIN'    | 'SIL_SI2343DS.pdf'                     | ''            | ''     | ''  | ''         | ''      | '20131205'
 'SI2333DDS-T1-GE3' | 'SMLF'    | 'IC'     | 'BAM23330001'(!)  = ''              | ''                 | 'BAM23330001'     |'SOT23_GDSXB'| 'TRANS MOS SI2333DDS-T1-GE3(12V,20A,1.7W)' | 'SIL'   | 'SI2333DDS-T1-GE3' | 'EP(V1)'     | ''        | 'IC'  | ''      | ''                     | 'S2B-ALVIN'    | 'SIL_SI2333DDS_revA.pdf'               | ''            | ''     | ''  | ''         | ''      | '20140213'
 'SI2333DDS-T1-GE3' | 'SMLF'    | 'EMPTY'  | 'BAM23330001'(!)  = ''              | ''                 | 'BAM23330001'     |'SOT23_GDSXB'| 'TRANS MOS SI2333DDS-T1-GE3(12V,20A,1.7W)' | 'SIL'   | 'SI2333DDS-T1-GE3' | 'EP(V1)'     | ''        | 'IC'  | ''      | ''                     | 'S2B-ALVIN'    | 'SIL_SI2333DDS_revA.pdf'               | ''            | ''     | ''  | ''         | ''      | '20140213'
 'AP4435GH'         | 'SMLF'    | 'IC'     | 'BAM44350070'(!)  = ''              | ''                 | 'BAM44350070'     |'TO252_GDSXB'| 'TRANS MOSFET AP4435GH(-30V,-40A,TO-252)'  | 'AVP'   | 'AP4435GH'         | 'EP(V1)'     | 'EP(V1)'  | 'IC'  | ''      | ''                     | 'T2R-GAVEN'    | 'AVP_AP4435GH_J-HF_rev201301244QT.pdf' | ''            | ''     | ''  | ''         | ''      | '20140708'
 'AP4435GH'         | 'SMLF'    | 'EMPTY'  | 'BAM44350070'(!)  = ''              | ''                 | 'BAM44350070'     |'TO252_GDSXB'| 'TRANS MOSFET AP4435GH(-30V,-40A,TO-252)'  | 'AVP'   | 'AP4435GH'         | 'EP(V1)'     | 'EP(V1)'  | 'IC'  | ''      | ''                     | 'T2R-GAVEN'    | 'AVP_AP4435GH_J-HF_rev201301244QT.pdf' | ''            | ''     | ''  | ''         | ''      | '20140708'
 'FDD6685_G'        | 'SMLF'    | 'IC'     | 'BAM66850000'(!)  = 'End of Design' | 'Comp-Approve'     | 'BAM66850000'     |'TO252_GDS'| 'TRANSMOSFET FDD6685_G(-30V,-40A,52W)'     | 'FAC'   | 'FDD6685_G'        | 'EP(V1)'     | 'EP(V1)'  | 'IC'  | ''      | ''                     | 'T2H-GAVEN'    | 'FDD6685_REV2004.pdf'                  | ''            | ''     | ''  | ''         | ''      | '20140826'
 'FDD6685_G'        | 'SMLF'    | 'EMPTY'  | 'BAM66850000'(!)  = 'End of Design' | 'Comp-Approve'     | 'BAM66850000'     |'TO252_GDS'| 'TRANSMOSFET FDD6685_G(-30V,-40A,52W)'     | 'FAC'   | 'FDD6685_G'        | 'EP(V1)'     | 'EP(V1)'  | 'IC'  | ''      | ''                     | 'T2H-GAVEN'    | 'FDD6685_REV2004.pdf'                  | ''            | ''     | ''  | ''         | ''      | '20140826'
 'IRLML6401TRPBF'   | 'SMLF'    | 'IC'     | 'BAM64010020'(!)  = 'End of Design' | 'Comp-Approve'     | 'BAM64010020'     |'SOT23_GDS_2-92X1-3'| 'TRANS MOSFET IRLML6401TRPBF(-12V-4.3A)EP' | 'ICL'   | 'IRLML6401TRPBF'   | 'EP'         | 'EP'      | 'IC'  | ''      | ''                     | 'T2H-GAVEN'    | 'ICL_IRLML6401TRPBF.pdf'               | ''            | ''     | ''  | ''         | ''      | '20141024'
 'IRLML6401TRPBF'   | 'SMLF'    | 'EMPTY'  | 'BAM64010020'(!)  = 'End of Design' | 'Comp-Approve'     | 'BAM64010020'     |'SOT23_GDS_2-92X1-3'| 'TRANS MOSFET IRLML6401TRPBF(-12V-4.3A)EP' | 'ICL'   | 'IRLML6401TRPBF'   | 'EP'         | 'EP'      | 'IC'  | ''      | ''                     | 'T2H-GAVEN'    | 'ICL_IRLML6401TRPBF.pdf'               | ''            | ''     | ''  | ''         | ''      | '20141024'
 'AO3401A'          | 'SMLF'    | 'IC'     | 'BAM34010001'(!)  = ''              | ''                 | 'BAM34010001'     |'SOT23_GDSXA'| 'TRANS MOSFET AO3401A(-30V,-4.3A)SOT23'    | 'AOS'   | 'AO3401A'          | 'EP'         | 'EU(V1)'  | 'IC'  | ''      | ''                     | 'T2H-GAVEN'    | 'AOS_AO3401A.pdf'                      | ''            | ''     | ''  | ''         | ''      | '20141024'
 'AO3401A'          | 'SMLF'    | 'EMPTY'  | 'BAM34010001'(!)  = ''              | ''                 | 'BAM34010001'     |'SOT23_GDSXA'| 'TRANS MOSFET AO3401A(-30V,-4.3A)SOT23'    | 'AOS'   | 'AO3401A'          | 'EP'         | 'EU(V1)'  | 'IC'  | ''      | ''                     | 'T2H-GAVEN'    | 'AOS_AO3401A.pdf'                      | ''            | ''     | ''  | ''         | ''      | '20141024'
 'AP2305GN'         | 'SMLF'    | 'IC'     | 'BAM23050027'(!)  = 'Non-Preferred' | 'End of Life'      | 'BAM23050027'     |'SOT23_GDS_2-9X1-3_EOL'| 'TRAN P-MOSFET AP2305GN-20V,1.38W(SOT-23)' | 'AVP'   | 'AP2305GN'         | 'EP(V1)'     | 'EP(V1)'  | 'IC'  | ''      | ''                     | 'S5A-CHIN'     | 'AVP_AP2305GN.pdf'                     | ''            | ''     | ''  | ''         | ''      | '20141201'
 'AP2305GN'         | 'SMLF'    | 'EMPTY'  | 'BAM23050027'(!)  = 'Non-Preferred' | 'End of Life'      | 'BAM23050027'     |'SOT23_GDS_2-9X1-3_EOL'| 'TRAN P-MOSFET AP2305GN-20V,1.38W(SOT-23)' | 'AVP'   | 'AP2305GN'         | 'EP(V1)'     | 'EP(V1)'  | 'IC'  | ''      | ''                     | 'S5A-CHIN'     | 'AVP_AP2305GN.pdf'                     | ''            | ''     | ''  | ''         | ''      | '20141201'
 'SUD45P03-09-GE3'  | 'SMLF'    | 'IC'     | 'BAM45030000'(!)  = ''              | ''                 | 'BAM45030000'     |'TO252_GDS'| 'TRANS MOS SUD45P03-09-GE(-30V,45A,41.7W)' | 'SIL'   | 'SUD45P03-09-GE3'  | 'EP(V1)'     | ''        | 'IC'  | ''      | 'RE BAM45030000.msg'   | 'JSA-MEALY'    | 'SIL_SUD45P03-09-GE3.pdf'              | ''            | ''     | ''  | ''         | ''      | '20150907'
 'SUD45P03-09-GE3'  | 'SMLF'    | 'EMPTY'  | 'BAM45030000'(!)  = ''              | ''                 | 'BAM45030000'     |'TO252_GDS'| 'TRANS MOS SUD45P03-09-GE(-30V,45A,41.7W)' | 'SIL'   | 'SUD45P03-09-GE3'  | 'EP(V1)'     | ''        | 'IC'  | ''      | 'RE BAM45030000.msg'   | 'JSA-MEALY'    | 'SIL_SUD45P03-09-GE3.pdf'              | ''            | ''     | ''  | ''         | ''      | '20150907'
 'DMP3028LK3-13'    | 'SMLF'    | 'IC'     | 'BAM30280000'(!)  = ''              | ''                 | 'BAM30280000'     |'TO252_GDSXC'| 'TRANS MOS DMP3028LK3-13(-30V,-27A,1.6W)'  | 'DDS'   | 'DMP3028LK3-13'    | 'EP(V1)'     | ''        | 'IC'  | ''      | ''                     | 'T2H-CF'       | 'DDS_DMP3028LK3-13.pdf'                | ''            | ''     | ''  | ''         | ''      | '20160323'
 'DMP3028LK3-13'    | 'SMLF'    | 'EMPTY'  | 'BAM30280000'(!)  = ''              | ''                 | 'BAM30280000'     |'TO252_GDSXC'| 'TRANS MOS DMP3028LK3-13(-30V,-27A,1.6W)'  | 'DDS'   | 'DMP3028LK3-13'    | 'EP(V1)'     | ''        | 'IC'  | ''      | ''                     | 'T2H-CF'       | 'DDS_DMP3028LK3-13.pdf'                | ''            | ''     | ''  | ''         | ''      | '20160323'
 'BSS84'            | 'SMLF'    | 'IC'     | 'BAM00840000'(!)  = 'End of Design' | 'Comp-Approve'     | 'BAM00840000'     |'SOT23_GDS_2-92X1-3XA'| 'TRANS MOSFET BSS84(50V 130MA)SOT23'       | 'FAC'   | 'BSS84'            | 'EP'         | 'EP'      | 'IC'  | ''      | ''                     | 'T2N-MARK'     | 'FAC_BSS84.pdf'                        | ''            | ''     | ''  | ''         | ''      | '20171020'
 'BSS84'            | 'SMLF'    | 'EMPTY'  | 'BAM00840000'(!)  = 'End of Design' | 'Comp-Approve'     | 'BAM00840000'     |'SOT23_GDS_2-92X1-3XA'| 'TRANS MOSFET BSS84(50V 130MA)SOT23'       | 'FAC'   | 'BSS84'            | 'EP'         | 'EP'      | 'IC'  | ''      | ''                     | 'T2N-MARK'     | 'FAC_BSS84.pdf'                        | ''            | ''     | ''  | ''         | ''      | '20171020'
 'IRLML6402TRPBF'   | 'SMLF'    | 'IC'     | 'BAM64020Z00'(!)  = ''              | ''                 | 'BAM64020Z00'     |'SOT23_GDS_2-92X1-3'| 'TRANS MOSFET IRLML6402TRPBF(20V,3.7A)'    | 'ICL'   | 'IRLML6402TRPBF'   | 'EP(V1)'     | 'EP(V1)'  | 'IC'  | ''      | ''                     | 'T2N-MARK'     | 'ICL_IRLML6402TRPBF.pdf'               | ''            | ''     | ''  | ''         | ''      | '20171101'
 'IRLML6402TRPBF'   | 'SMLF'    | 'EMPTY'  | 'BAM64020Z00'(!)  = ''              | ''                 | 'BAM64020Z00'     |'SOT23_GDS_2-92X1-3'| 'TRANS MOSFET IRLML6402TRPBF(20V,3.7A)'    | 'ICL'   | 'IRLML6402TRPBF'   | 'EP(V1)'     | 'EP(V1)'  | 'IC'  | ''      | ''                     | 'T2N-MARK'     | 'ICL_IRLML6402TRPBF.pdf'               | ''            | ''     | ''  | ''         | ''      | '20171101'
 'PMV32UP'          | 'SMLF'    | 'IC'     | 'BAM32UPZ000'(!)  = ''              | ''                 | 'BAM32UPZ000'     |'SOT23_GDSXE'| 'TRANS MOS PMV32UP(-20V,-4A,510MW)'        | 'NXP'   | 'PMV32UP'          | 'EP(V1)'     | 'EP(V1)'  | 'IC'  | ''      | ''                     | 'S6V-KATE'     | 'NXP_PMV32UP.pdf'                      | ''            | ''     | ''  | ''         | ''      | '20181226'
 'PMV32UP'          | 'SMLF'    | 'EMPTY'  | 'BAM32UPZ000'(!)  = ''              | ''                 | 'BAM32UPZ000'     |'SOT23_GDSXE'| 'TRANS MOS PMV32UP(-20V,-4A,510MW)'        | 'NXP'   | 'PMV32UP'          | 'EP(V1)'     | 'EP(V1)'  | 'IC'  | ''      | ''                     | 'S6V-KATE'     | 'NXP_PMV32UP.pdf'                      | ''            | ''     | ''  | ''         | ''      | '20181226'
 'BSS84-7-F'        | 'SMLF'    | 'IC'     | 'BAMSS840000'(!)  = ''              | ''                 | 'BAMSS840000'     |'SOT23_GDSXC'| 'TRAN MOS BSS84-7-F(50V,130MA,0.3W)SOT-23' | 'DDS'   | 'BSS84-7-F'        | 'EP(V1)'     | 'EP(V1)'  | 'IC'  | ''      | ''                     | 'JBP-DEAN'     | 'DDS_BSS84-7-F.pdf'                    | ''            | ''     | ''  | ''         | ''      | '20190102'
 'BSS84-7-F'        | 'SMLF'    | 'EMPTY'  | 'BAMSS840000'(!)  = ''              | ''                 | 'BAMSS840000'     |'SOT23_GDSXC'| 'TRAN MOS BSS84-7-F(50V,130MA,0.3W)SOT-23' | 'DDS'   | 'BSS84-7-F'        | 'EP(V1)'     | 'EP(V1)'  | 'IC'  | ''      | ''                     | 'JBP-DEAN'     | 'DDS_BSS84-7-F.pdf'                    | ''            | ''     | ''  | ''         | ''      | '20190102'
 'BSS84LT1G'        | 'SMLF'    | 'IC'     | 'BAM00840005'(!)  = 'End of Design' | 'Comp-Approve'     | 'BAM00840005'     |'SOT23_GDSXC'| 'TRANS MOS BSS84LT1G(50V130MA,225MW,SOT23' | 'ONS'   | 'BSS84LT1G'        | 'EP(V1)'     | 'EP(V1)'  | 'IC'  | ''      | ''                     | 'S8I-KENNY'    | 'ONS_BSS84LT1G.pdf'                    | ''            | ''     | ''  | ''         | ''      | '20200219'
 'BSS84LT1G'        | 'SMLF'    | 'EMPTY'  | 'BAM00840005'(!)  = 'End of Design' | 'Comp-Approve'     | 'BAM00840005'     |'SOT23_GDSXC'| 'TRANS MOS BSS84LT1G(50V130MA,225MW,SOT23' | 'ONS'   | 'BSS84LT1G'        | 'EP(V1)'     | 'EP(V1)'  | 'IC'  | ''      | ''                     | 'S8I-KENNY'    | 'ONS_BSS84LT1G.pdf'                    | ''            | ''     | ''  | ''         | ''      | '20200219'
 'NTR1P02LT1G'      | 'SMLF'    | 'IC'     | 'BAM1P020000'(!)  = 'End of Design' | 'Comp-Approve'     | 'BAM1P020000'     |'SOT23_GDS_2-9X1-3XC'| 'TRANS MOSFET NTR1P02LT1G(-20V,SOT-23)'    | 'ONS'   | 'NTR1P02LT1G'      | 'EP(V1)'     | 'EP(V1)'  | 'IC'  | ''      | ''                     | 'JG7-ALLEN'    | 'ONS_NTR1P02LT1G.pdf'                  | ''            | ''     | ''  | ''         | ''      | '20200907'
 'NTR1P02LT1G'      | 'SMLF'    | 'EMPTY'  | 'BAM1P020000'(!)  = 'End of Design' | 'Comp-Approve'     | 'BAM1P020000'     |'SOT23_GDS_2-9X1-3XC'| 'TRANS MOSFET NTR1P02LT1G(-20V,SOT-23)'    | 'ONS'   | 'NTR1P02LT1G'      | 'EP(V1)'     | 'EP(V1)'  | 'IC'  | ''      | ''                     | 'JG7-ALLEN'    | 'ONS_NTR1P02LT1G.pdf'                  | ''            | ''     | ''  | ''         | ''      | '20200907'
 'BSS84W-7-F'       | 'SMLF'    | 'IC'     | 'BAM00840014'(!)  = ''              | ''                 | 'BAM00840014'     |'SOT323_GDS_2-15X1-3XA'| 'TRANS MOS BSS84W-7-F(-50V,-130MA,0.2W)SO' | 'DDS'   | 'BSS84W-7-F'       | 'EP(V1)'     | 'EP(V1)'  | 'IC'  | ''      | ''                     | 'IXD-WILL'     | 'DDS_BSS84W-7-F.pdf'                   | ''            | ''     | ''  | ''         | ''      | '20201103'
 'BSS84W-7-F'       | 'SMLF'    | 'EMPTY'  | 'BAM00840014'(!)  = ''              | ''                 | 'BAM00840014'     |'SOT323_GDS_2-15X1-3XA'| 'TRANS MOS BSS84W-7-F(-50V,-130MA,0.2W)SO' | 'DDS'   | 'BSS84W-7-F'       | 'EP(V1)'     | 'EP(V1)'  | 'IC'  | ''      | ''                     | 'IXD-WILL'     | 'DDS_BSS84W-7-F.pdf'                   | ''            | ''     | ''  | ''         | ''      | '20201103'
 'IRFR5410PBF'      | 'SMLF'    | 'IC'     | 'BAM54100001'(!)  = ''              | ''                 | 'BAM54100001'     |'TO252AA_GDS_6-54X6-095'| 'TRANS MOS IRFR5410PBF(20V,-52A,66W)'      | 'SNI'   | 'IRFR5410PBF'      | 'EP(V1)'     | ''        | 'IC'  | ''      | ''                     | '2RE-WAYNE'    | 'SNI_IRFR5410PBF.pdf'                  | ''            | ''     | ''  | ''         | ''      | '20210422'
 'IRFR5410PBF'      | 'SMLF'    | 'EMPTY'  | 'BAM54100001'(!)  = ''              | ''                 | 'BAM54100001'     |'TO252AA_GDS_6-54X6-095'| 'TRANS MOS IRFR5410PBF(20V,-52A,66W)'      | 'SNI'   | 'IRFR5410PBF'      | 'EP(V1)'     | ''        | 'IC'  | ''      | ''                     | '2RE-WAYNE'    | 'SNI_IRFR5410PBF.pdf'                  | ''            | ''     | ''  | ''         | ''      | '20210422'
 'FDN86265P'        | 'SMLF'    | 'IC'     | 'BAM86260000'(!)  = 'End of Design' | 'Comp-Release Qty' | 'BAM86260000'     |'SOT23_GDS_2-92X1-4'| 'TRANS MOS FDN86265P(-150V,-0.8A,1.5W)'    | 'ONS'   | 'FDN86265P'        | 'EP(V1)'     | ''        | 'IC'  | ''      | 'FDN86265P.msg'        | 'S8Z-JW'       | 'ONS_FDN86265P.pdf'                    | ''            | ''     | ''  | ''         | ''      | '20210426'
 'FDN86265P'        | 'SMLF'    | 'EMPTY'  | 'BAM86260000'(!)  = 'End of Design' | 'Comp-Release Qty' | 'BAM86260000'     |'SOT23_GDS_2-92X1-4'| 'TRANS MOS FDN86265P(-150V,-0.8A,1.5W)'    | 'ONS'   | 'FDN86265P'        | 'EP(V1)'     | ''        | 'IC'  | ''      | 'FDN86265P.msg'        | 'S8Z-JW'       | 'ONS_FDN86265P.pdf'                    | ''            | ''     | ''  | ''         | ''      | '20210426'
 'SI2325DS-T1-GE3'  | 'SMLF'    | 'IC'     | 'BAM23250001'(!)  = 'End of Design' | 'Comp-Release Qty' | 'BAM23250001'     |'SOT23_GDSXB'| 'TRANS MOS SI2325DS-T(-150V,-0.69A,1.25W)' | 'SIL'   | 'SI2325DS-T1-GE3'  | 'EP(V1)'     | ''        | 'IC'  | ''      | 'SI2325DS-T1-GE3.msg'  | 'T2M-LEO'      | 'SIL_SI2325DS-T1-GE3.pdf'              | ''            | ''     | ''  | ''         | ''      | '20210705'
 'SI2325DS-T1-GE3'  | 'SMLF'    | 'EMPTY'  | 'BAM23250001'(!)  = 'End of Design' | 'Comp-Release Qty' | 'BAM23250001'     |'SOT23_GDSXB'| 'TRANS MOS SI2325DS-T(-150V,-0.69A,1.25W)' | 'SIL'   | 'SI2325DS-T1-GE3'  | 'EP(V1)'     | ''        | 'IC'  | ''      | 'SI2325DS-T1-GE3.msg'  | 'T2M-LEO'      | 'SIL_SI2325DS-T1-GE3.pdf'              | ''            | ''     | ''  | ''         | ''      | '20210705'
 'FQD17P06TM'       | 'SMLF'    | 'IC'     | 'BAM17P00000'(!)  = ''              | ''                 | 'BAM17P00000'     |'DPAK_GDS_6-54X6-095'| 'TRANS MOSFET FQD17P06TM(-60V,-12A,44W)'   | 'ONS'   | 'FQD17P06TM'       | 'EP(V1)'     | ''        | 'IC'  | ''      | 'FQD17P06TM.msg'       | 'E3DE-JACK'    | 'ONS_FQD17P06TM.pdf'                   | ''            | ''     | ''  | ''         | ''      | '20210802'
 'FQD17P06TM'       | 'SMLF'    | 'EMPTY'  | 'BAM17P00000'(!)  = ''              | ''                 | 'BAM17P00000'     |'DPAK_GDS_6-54X6-095'| 'TRANS MOSFET FQD17P06TM(-60V,-12A,44W)'   | 'ONS'   | 'FQD17P06TM'       | 'EP(V1)'     | ''        | 'IC'  | ''      | 'FQD17P06TM.msg'       | 'E3DE-JACK'    | 'ONS_FQD17P06TM.pdf'                   | ''            | ''     | ''  | ''         | ''      | '20210802'
 'SUD09P10-195-GE3' | 'SMLF'    | 'IC'     | 'BAM01950000'(!)  = ''              | ''                 | 'BAM01950000'     |'TO252AA_GDS_6-54X6-095XA'| 'TRANS MOS SUD09P10(100V,-8.8A,32.1W)'     | 'SIL'   | 'SUD09P10-195-GE3' | 'EP(V1)'     | ''        | 'IC'  | ''      | 'SUD09P10-195-GE3.msg' | '2RE-JASON'    | 'SIL_SUD09P10-195-GE3.pdf'             | ''            | ''     | ''  | ''         | ''      | '20211013'
 'SUD09P10-195-GE3' | 'SMLF'    | 'EMPTY'  | 'BAM01950000'(!)  = ''              | ''                 | 'BAM01950000'     |'TO252AA_GDS_6-54X6-095XA'| 'TRANS MOS SUD09P10(100V,-8.8A,32.1W)'     | 'SIL'   | 'SUD09P10-195-GE3' | 'EP(V1)'     | ''        | 'IC'  | ''      | 'SUD09P10-195-GE3.msg' | '2RE-JASON'    | 'SIL_SUD09P10-195-GE3.pdf'             | ''            | ''     | ''  | ''         | ''      | '20211013'
 'DMP610DL-7'       | 'SMLF'    | 'IC'     | 'BAM06100006'(!)  = ''              | ''                 | 'BAM06100006'     |'SOT23_GDSXC'| 'TRANMOS DMP610DL-7(60V,0.18A,0.31W)SOT23' | 'DDS'   | 'DMP610DL-7'       | 'EP(V1)'     | 'EP(V1)'  | 'IC'  | ''      | ''                     | 'MF6-STEVEN'   | 'DDS_DMP610DL-7.pdf'                   | ''            | ''     | ''  | ''         | ''      | '20230113'
 'DMP610DL-7'       | 'SMLF'    | 'EMPTY'  | 'BAM06100006'(!)  = ''              | ''                 | 'BAM06100006'     |'SOT23_GDSXC'| 'TRANMOS DMP610DL-7(60V,0.18A,0.31W)SOT23' | 'DDS'   | 'DMP610DL-7'       | 'EP(V1)'     | 'EP(V1)'  | 'IC'  | ''      | ''                     | 'MF6-STEVEN'   | 'DDS_DMP610DL-7.pdf'                   | ''            | ''     | ''  | ''         | ''      | '20230113'
 'DMG2305UX-7'      | 'SMLF'    | 'IC'     | 'BAM23050008'(!)  = ''              | ''                 | 'BAM23050008'     |'SOT23_GDSXC'| 'TRANS MOS DMG2305UX-7(20V,4.2A,1.4W)'     | 'DDS'   | 'DMG2305UX-7'      | 'EP(V1)'     | 'EP(V1)'  | 'IC'  | ''      | ''                     | 'F0EG-PATRICK' | 'DDS_DMG2305UX-7.pdf'                  | ''            | ''     | ''  | ''         | ''      | '20230327'
 'DMG2305UX-7'      | 'SMLF'    | 'EMPTY'  | 'BAM23050008'(!)  = ''              | ''                 | 'BAM23050008'     |'SOT23_GDSXC'| 'TRANS MOS DMG2305UX-7(20V,4.2A,1.4W)'     | 'DDS'   | 'DMG2305UX-7'      | 'EP(V1)'     | 'EP(V1)'  | 'IC'  | ''      | ''                     | 'F0EG-PATRICK' | 'DDS_DMG2305UX-7.pdf'                  | ''            | ''     | ''  | ''         | ''      | '20230327'
 'IRLML6401TRPBF'   | 'SMLF'    | 'IC'     | 'BAM64010020SEL1'(!) = ''              | ''               | 'BAM64010020SEL1' |'SOT23_GDS_2-92X1-3'| 'TRANS MOS IRLML6401TR(-12V-4.3A1.3W)SELA' | 'ICL'   | 'IRLML6401TRPBF'   | 'EP'         | 'EP'      | 'IC'  | ''      | 'SEL_15QPN.xlsx'       | 'T2H-GAVEN'    | 'ICL_IRLML6401TRPBF.pdf'               | ''            | ''     | ''  | ''         | ''      | '20230626'
 'IRLML6401TRPBF'   | 'SMLF'    | 'EMPTY'  | 'BAM64010020SEL1'(!) = ''              | ''               | 'BAM64010020SEL1' |'SOT23_GDS_2-92X1-3'| 'TRANS MOS IRLML6401TR(-12V-4.3A1.3W)SELA' | 'ICL'   | 'IRLML6401TRPBF'   | 'EP'         | 'EP'      | 'IC'  | ''      | 'SEL_15QPN.xlsx'       | 'T2H-GAVEN'    | 'ICL_IRLML6401TRPBF.pdf'               | ''            | ''     | ''  | ''         | ''      | '20230626'
 'FDN86265P'        | 'SMLF'    | 'IC'     | 'BAM86260000SEL1'(!) = ''              | ''               | 'BAM86260000SEL1' |'SOT23_GDS_2-92X1-4'| 'TRANSMOS FDN86265P(-150V,-0.8A,1.5W)SELA' | 'ONS'   | 'FDN86265P'        | 'EP(V1)'     | ''        | 'IC'  | ''      | 'SEL_15QPN.xlsx'       | 'S8Z-JW'       | 'ONS_FDN86265P.pdf'                    | ''            | ''     | ''  | ''         | ''      | '20230626'
 'FDN86265P'        | 'SMLF'    | 'EMPTY'  | 'BAM86260000SEL1'(!) = ''              | ''               | 'BAM86260000SEL1' |'SOT23_GDS_2-92X1-4'| 'TRANSMOS FDN86265P(-150V,-0.8A,1.5W)SELA' | 'ONS'   | 'FDN86265P'        | 'EP(V1)'     | ''        | 'IC'  | ''      | 'SEL_15QPN.xlsx'       | 'S8Z-JW'       | 'ONS_FDN86265P.pdf'                    | ''            | ''     | ''  | ''         | ''      | '20230626'
 'BSS84-7-F'        | 'SMLF'    | 'IC'     | 'BAMSS840000SEL1'(!) = ''              | ''               | 'BAMSS840000SEL1' |'SOT23_GDSXC'| 'TRANS MOS BSS84-7(50V,0.13A,0.3W)SELA'    | 'DDS'   | 'BSS84-7-F'        | 'EP(V1)'     | 'EP(V1)'  | 'IC'  | ''      | 'SEL_15QPN.xlsx'       | 'JBP-DEAN'     | 'DDS_BSS84-7-F.pdf'                    | ''            | ''     | ''  | ''         | ''      | '20230626'
 'BSS84-7-F'        | 'SMLF'    | 'EMPTY'  | 'BAMSS840000SEL1'(!) = ''              | ''               | 'BAMSS840000SEL1' |'SOT23_GDSXC'| 'TRANS MOS BSS84-7(50V,0.13A,0.3W)SELA'    | 'DDS'   | 'BSS84-7-F'        | 'EP(V1)'     | 'EP(V1)'  | 'IC'  | ''      | 'SEL_15QPN.xlsx'       | 'JBP-DEAN'     | 'DDS_BSS84-7-F.pdf'                    | ''            | ''     | ''  | ''         | ''      | '20230626'

END_PART

END.

